# BASEBOARD_FAB2 (Tioga Pass) — schematic netlist excerpt (pin names and nets, part order shuffled) for the footprints in the layout excerpt that follows; sources: Cadence DE-HDL packaged netlist, KiCad conversion of Wiwynn_Tioga_Pass_MB.brd

R9M3  RES  0.0 5% CHIP  pkg 0402  page 226 : A = P3V3_STBY ; B = VR_PVDDQ_KLM_VDD
C8P9  CAP  100UF 4V 20% X5R  pkg 0805  page 76 : A = PVCCMCP_CPU1 ; B = GND
R32W6  RES  2.0K 1% CHIP  pkg 0402  page 185 : A = P1V8_M2 ; B = SMB_M2_SDA

(kicad_pcb
	(version 20260206)
	(generator "pcbnew")
	(generator_version "10.0")
	(general
		(thickness 1.6)
		(legacy_teardrops no)
	)
	(paper "A4")
	(title_block
		(title "Wiwynn_Tioga_Pass_MB.brd")
		(comment 1 "Tioga Pass / footprints 2905-2907 of 4770")
	)
	(layers
		(0 "F.Cu" signal "TOP")
		(4 "In1.Cu" signal "L2GND")
		(6 "In2.Cu" signal "L3")
		(8 "In3.Cu" signal "L4GND")
		(10 "In4.Cu" signal "L5")
		(12 "In5.Cu" signal "L6GND")
		(14 "In6.Cu" signal "L7VCC")
		(16 "In7.Cu" signal "L8VCC")
		(18 "In8.Cu" signal "L9GND")
		(20 "In9.Cu" signal "L10")
		(22 "In10.Cu" signal "L11GND")
		(24 "In11.Cu" signal "L12")
		(26 "In12.Cu" signal "L13GND")
		(2 "B.Cu" signal "BOTTOM")
		(9 "F.Adhes" user "F.Adhesive")
		(11 "B.Adhes" user "B.Adhesive")
		(13 "F.Paste" user "Package Geometry/Pastemask Top")
		(15 "B.Paste" user "Package Geometry/Pastemask Bottom")
		(5 "F.SilkS" user "Ref Des/Silkscreen Top")
		(7 "B.SilkS" user "Ref Des/Silkscreen Bottom")
		(1 "F.Mask" user "Board Geometry/Soldermask Top")
		(3 "B.Mask" user "Board Geometry/Soldermask Bottom")
		(17 "Dwgs.User" user "User.Drawings")
		(19 "Cmts.User" user "User.Comments")
		(21 "Eco1.User" user "User.Eco1")
		(23 "Eco2.User" user "User.Eco2")
		(25 "Edge.Cuts" user "Board Geometry/Outline")
		(27 "Margin" user)
		(31 "F.CrtYd" user "Package Geometry/Place Bound Top")
		(29 "B.CrtYd" user "Package Geometry/Place Bound Bottom")
		(35 "F.Fab" user "Ref Des/Assembly Top")
		(33 "B.Fab" user "Ref Des/Assembly Bottom")
	)
	(footprint ""
		(layer "B.Cu")
		(at 8.0264 -132.3594)
		(property "Reference" "R9M3"
			(at 0 0 0)
			(layer "B.SilkS")
			(hide yes)
			(effects
				(font
					(size 1.27 1.27)
				)
				(justify mirror)
			)
		)
		(property "Value" ""
			(at 0 0 0)
			(layer "B.Fab")
			(effects
				(font
					(size 1.27 1.27)
				)
				(justify mirror)
			)
		)
		(duplicate_pad_numbers_are_jumpers no)
		(fp_rect
			(start -0.2794 0.9906)
			(end 0.2794 -0.1016)
			(stroke
				(width 0)
				(type default)
			)
			(fill no)
			(layer "B.CrtYd")
		)
		(fp_line
			(start -0.2794 -0.1016)
			(end 0.2794 -0.1016)
			(stroke
				(width 0.1)
				(type default)
			)
			(layer "B.Fab")
		)
		(fp_line
			(start -0.2794 0.9906)
			(end -0.2794 -0.1016)
			(stroke
				(width 0.1)
				(type default)
			)
			(layer "B.Fab")
		)
		(fp_line
			(start 0.2794 -0.1016)
			(end 0.2794 0.9906)
			(stroke
				(width 0.1)
				(type default)
			)
			(layer "B.Fab")
		)
		(fp_line
			(start 0.2794 0.9906)
			(end -0.2794 0.9906)
			(stroke
				(width 0.1)
				(type default)
			)
			(layer "B.Fab")
		)
		(pad "1" smd rect
			(at 0 0 180)
			(size 0.508 0.508)
			(layers "B.Cu" "B.Mask" "B.Paste")
			(net "P3V3_STBY")
		)
		(pad "2" smd rect
			(at 0 0.889 180)
			(size 0.508 0.508)
			(layers "B.Cu" "B.Mask" "B.Paste")
			(net "VR_PVDDQ_KLM_VDD")
		)
		(zone
			(layer "B.Cu")
			(hatch none 0.5)
			(connect_pads
				(clearance 0)
			)
			(min_thickness 0.25)
			(keepout
				(tracks not_allowed)
				(vias allowed)
				(pads allowed)
				(copperpour not_allowed)
				(footprints allowed)
			)
			(placement
				(enabled no)
				(sheetname "")
			)
			(fill
				(thermal_gap 0.5)
				(thermal_bridge_width 0.5)
				(island_removal_mode 0)
			)
			(polygon
				(pts
					(xy 7.7724 -131.7244) (xy 8.2804 -131.7244) (xy 8.2804 -132.1054) (xy 7.7724 -132.1054)
				)
			)
		)
		(zone
			(layer "B.Cu")
			(hatch none 0.5)
			(connect_pads
				(clearance 0)
			)
			(min_thickness 0.25)
			(keepout
				(tracks allowed)
				(vias not_allowed)
				(pads allowed)
				(copperpour not_allowed)
				(footprints allowed)
			)
			(placement
				(enabled no)
				(sheetname "")
			)
			(fill
				(thermal_gap 0.5)
				(thermal_bridge_width 0.5)
				(island_removal_mode 0)
			)
			(polygon
				(pts
					(xy 7.7724 -131.7244) (xy 8.2804 -131.7244) (xy 8.2804 -132.1054) (xy 7.7724 -132.1054)
				)
			)
		)
	)
	(footprint ""
		(layer "B.Cu")
		(at 396.216886 -16.438372 180)
		(property "Reference" "R32W6"
			(at 0.8382 -0.67818 180)
			(unlocked yes)
			(layer "B.SilkS")
			(effects
				(font
					(size 0.4064 0.254)
					(thickness 0.1524)
				)
				(justify left mirror)
			)
		)
		(property "Value" ""
			(at 0 0 0)
			(layer "B.Fab")
			(effects
				(font
					(size 1.27 1.27)
				)
				(justify mirror)
			)
		)
		(duplicate_pad_numbers_are_jumpers no)
		(fp_poly
			(pts
				(xy 0.2794 -0.1016) (xy -0.2794 -0.1016) (xy -0.2794 0.9906) (xy 0.2794 0.9906)
			)
			(stroke
				(width 0)
				(type default)
			)
			(fill no)
			(layer "B.CrtYd")
		)
		(fp_line
			(start 0.2794 0.9906)
			(end -0.2794 0.9906)
			(stroke
				(width 0.1)
				(type default)
			)
			(layer "B.Fab")
		)
		(fp_line
			(start 0.2794 -0.1016)
			(end 0.2794 0.9906)
			(stroke
				(width 0.1)
				(type default)
			)
			(layer "B.Fab")
		)
		(fp_line
			(start -0.2794 0.9906)
			(end -0.2794 -0.1016)
			(stroke
				(width 0.1)
				(type default)
			)
			(layer "B.Fab")
		)
		(fp_line
			(start -0.2794 -0.1016)
			(end 0.2794 -0.1016)
			(stroke
				(width 0.1)
				(type default)
			)
			(layer "B.Fab")
		)
		(pad "1" smd rect
			(at 0 0)
			(size 0.508 0.508)
			(layers "B.Cu" "B.Mask" "B.Paste")
			(net "P1V8_M2")
		)
		(pad "2" smd rect
			(at 0 0.889)
			(size 0.508 0.508)
			(layers "B.Cu" "B.Mask" "B.Paste")
			(net "SMB_M2_SDA")
		)
		(zone
			(layer "B.Cu")
			(hatch none 0.5)
			(connect_pads
				(clearance 0)
			)
			(min_thickness 0.25)
			(keepout
				(tracks not_allowed)
				(vias allowed)
				(pads allowed)
				(copperpour not_allowed)
				(footprints allowed)
			)
			(placement
				(enabled no)
				(sheetname "")
			)
			(fill
				(thermal_gap 0.5)
				(thermal_bridge_width 0.5)
				(island_removal_mode 0)
			)
			(polygon
				(pts
					(xy 395.962886 -17.073372) (xy 396.470886 -17.073372) (xy 396.470886 -16.692372) (xy 395.962886 -16.692372)
				)
			)
		)
		(zone
			(layer "B.Cu")
			(hatch none 0.5)
			(connect_pads
				(clearance 0)
			)
			(min_thickness 0.25)
			(keepout
				(tracks allowed)
				(vias not_allowed)
				(pads allowed)
				(copperpour not_allowed)
				(footprints allowed)
			)
			(placement
				(enabled no)
				(sheetname "")
			)
			(fill
				(thermal_gap 0.5)
				(thermal_bridge_width 0.5)
				(island_removal_mode 0)
			)
			(polygon
				(pts
					(xy 395.962886 -16.692372) (xy 396.470886 -16.692372) (xy 396.470886 -17.073372) (xy 395.962886 -17.073372)
				)
			)
		)
	)
	(footprint ""
		(layer "B.Cu")
		(at 104.902254 -79.60614 180)
		(property "Reference" "C8P9"
			(at 0 0 0)
			(layer "B.SilkS")
			(hide yes)
			(effects
				(font
					(size 1.27 1.27)
				)
				(justify mirror)
			)
		)
		(property "Value" ""
			(at 0 0 0)
			(layer "B.Fab")
			(effects
				(font
					(size 1.27 1.27)
				)
				(justify mirror)
			)
		)
		(duplicate_pad_numbers_are_jumpers no)
		(fp_poly
			(pts
				(xy 0.7239 -0.2159) (xy -0.7239 -0.2159) (xy -0.7239 1.9939) (xy 0.7239 1.9939)
			)
			(stroke
				(width 0)
				(type default)
			)
			(fill no)
			(layer "B.CrtYd")
		)
		(fp_line
			(start 0.7239 1.9939)
			(end -0.7239 1.9939)
			(stroke
				(width 0.1)
				(type default)
			)
			(layer "B.Fab")
		)
		(fp_line
			(start 0.7239 -0.2159)
			(end 0.7239 1.9939)
			(stroke
				(width 0.1)
				(type default)
			)
			(layer "B.Fab")
		)
		(fp_line
			(start -0.7239 1.9939)
			(end -0.7239 -0.2159)
			(stroke
				(width 0.1)
				(type default)
			)
			(layer "B.Fab")
		)
		(fp_line
			(start -0.7239 -0.2159)
			(end 0.7239 -0.2159)
			(stroke
				(width 0.1)
				(type default)
			)
			(layer "B.Fab")
		)
		(pad "1" smd rect
			(at 0 0)
			(size 1.27 1.016)
			(layers "B.Cu" "B.Mask" "B.Paste")
			(net "PVCCMCP_CPU1")
		)
		(pad "2" smd rect
			(at 0 1.778)
			(size 1.27 1.016)
			(layers "B.Cu" "B.Mask" "B.Paste")
			(net "GND")
		)
		(zone
			(layer "B.Cu")
			(hatch none 0.5)
			(connect_pads
				(clearance 0)
			)
			(min_thickness 0.25)
			(keepout
				(tracks not_allowed)
				(vias allowed)
				(pads allowed)
				(copperpour not_allowed)
				(footprints allowed)
			)
			(placement
				(enabled no)
				(sheetname "")
			)
			(fill
				(thermal_gap 0.5)
				(thermal_bridge_width 0.5)
				(island_removal_mode 0)
			)
			(polygon
				(pts
					(xy 104.267254 -80.11414) (xy 105.537254 -80.11414) (xy 105.537254 -80.87614) (xy 104.267254 -80.87614)
				)
			)
		)
	)
)
